(kicad_pcb
	(version 20260206)
	(generator "pcbnew")
	(generator_version "10.0")
	(general
		(thickness 1.6)
		(legacy_teardrops no)
	)
	(paper "A4")
	(title_block
		(title "01162023_DA0F0TEBIF0_F0T_Expander_BD_F_brd_V02_OCP.brd")
		(comment 1 "Grand Teton / footprints 4569-4574 of 9728")
	)
	(layers
		(0 "F.Cu" signal "TOP")
		(4 "In1.Cu" signal "GND")
		(6 "In2.Cu" signal "VCC")
		(8 "In3.Cu" signal "VCC1")
		(10 "In4.Cu" signal "GND1")
		(12 "In5.Cu" signal "IN1")
		(14 "In6.Cu" signal "GND2")
		(16 "In7.Cu" signal "IN2")
		(18 "In8.Cu" signal "GND3")
		(20 "In9.Cu" signal "IN3")
		(22 "In10.Cu" signal "GND4")
		(24 "In11.Cu" signal "IN4")
		(26 "In12.Cu" signal "GND5")
		(28 "In13.Cu" signal "IN5")
		(30 "In14.Cu" signal "GND6")
		(32 "In15.Cu" signal "IN6")
		(34 "In16.Cu" signal "GND7")
		(2 "B.Cu" signal "BOTTOM")
		(9 "F.Adhes" user "F.Adhesive")
		(11 "B.Adhes" user "B.Adhesive")
		(13 "F.Paste" user "Package Geometry/Pastemask Top")
		(15 "B.Paste" user "Package Geometry/Pastemask Bottom")
		(5 "F.SilkS" user "Ref Des/Silkscreen Top")
		(7 "B.SilkS" user "Ref Des/Silkscreen Bottom")
		(1 "F.Mask" user "Board Geometry/Soldermask Top")
		(3 "B.Mask" user "Board Geometry/Soldermask Bottom")
		(17 "Dwgs.User" user "User.Drawings")
		(19 "Cmts.User" user "User.Comments")
		(21 "Eco1.User" user "User.Eco1")
		(23 "Eco2.User" user "User.Eco2")
		(25 "Edge.Cuts" user "Board Geometry/Outline")
		(27 "Margin" user)
		(31 "F.CrtYd" user "Package Geometry/Place Bound Top")
		(29 "B.CrtYd" user "Package Geometry/Place Bound Bottom")
		(35 "F.Fab" user "Ref Des/Assembly Top")
		(33 "B.Fab" user "Ref Des/Assembly Bottom")
	)
	(footprint ""
		(layer "F.Cu")
		(at 414.197292 -178.532282)
		(property "Reference" "Q234"
			(at -3.784092 -1.592834 0)
			(unlocked yes)
			(layer "F.SilkS")
			(effects
				(font
					(size 0.7874 0.5842)
					(thickness 0.1524)
				)
			)
		)
		(property "Value" ""
			(at 0 0 0)
			(layer "F.Fab")
			(effects
				(font
					(size 1.27 1.27)
				)
			)
		)
		(duplicate_pad_numbers_are_jumpers no)
		(fp_line
			(start -1.376172 -1.199896)
			(end -0.508 -1.199896)
			(stroke
				(width 0.1524)
				(type default)
			)
			(layer "F.SilkS")
		)
		(fp_line
			(start -1.376172 1.199896)
			(end -1.376172 -1.199896)
			(stroke
				(width 0.1524)
				(type default)
			)
			(layer "F.SilkS")
		)
		(fp_line
			(start -0.508 -1.199896)
			(end 0 -0.762)
			(stroke
				(width 0.1524)
				(type default)
			)
			(layer "F.SilkS")
		)
		(fp_line
			(start 0 -0.762)
			(end 0.508 -1.199896)
			(stroke
				(width 0.1524)
				(type default)
			)
			(layer "F.SilkS")
		)
		(fp_line
			(start 0.508 -1.199896)
			(end 1.376172 -1.199896)
			(stroke
				(width 0.1524)
				(type default)
			)
			(layer "F.SilkS")
		)
		(fp_line
			(start 1.376172 -1.199896)
			(end 1.376172 1.199896)
			(stroke
				(width 0.1524)
				(type default)
			)
			(layer "F.SilkS")
		)
		(fp_line
			(start 1.376172 1.199896)
			(end -1.376172 1.199896)
			(stroke
				(width 0.1524)
				(type default)
			)
			(layer "F.SilkS")
		)
		(fp_poly
			(pts
				(xy -1.4605 -0.7493) (xy -2.2225 -1.1303) (xy -2.2225 -0.3683)
			)
			(stroke
				(width 0)
				(type default)
			)
			(fill yes)
			(layer "F.SilkS")
		)
		(fp_line
			(start -0.674878 -1.100074)
			(end 0.674878 -1.100074)
			(stroke
				(width 0.1)
				(type default)
			)
			(layer "F.Fab")
		)
		(fp_line
			(start -0.674878 1.100074)
			(end -0.674878 -1.100074)
			(stroke
				(width 0.1)
				(type default)
			)
			(layer "F.Fab")
		)
		(fp_line
			(start 0.674878 -1.100074)
			(end 0.674878 1.100074)
			(stroke
				(width 0.1)
				(type default)
			)
			(layer "F.Fab")
		)
		(fp_line
			(start 0.674878 1.100074)
			(end -0.674878 1.100074)
			(stroke
				(width 0.1)
				(type default)
			)
			(layer "F.Fab")
		)
		(fp_poly
			(pts
				(xy -1.4605 -0.7493) (xy -2.2225 -1.1303) (xy -2.2225 -0.3683)
			)
			(stroke
				(width 0)
				(type default)
			)
			(fill yes)
			(layer "F.Fab")
		)
		(pad "1" smd rect
			(at -0.899922 -0.750062 270)
			(size 0.6096 0.6096)
			(layers "F.Cu" "F.Mask" "F.Paste")
			(net "GND")
		)
		(pad "2" smd rect
			(at -0.899922 0 270)
			(size 0.4064 0.6096)
			(layers "F.Cu" "F.Mask" "F.Paste")
			(net "FPGA_PEX1_MODE_SEL1_R")
		)
		(pad "3" smd rect
			(at -0.899922 0.750062 270)
			(size 0.6096 0.6096)
			(layers "F.Cu" "F.Mask" "F.Paste")
			(net "FPGA_PEX1_MODE_SEL1_ISO")
		)
		(pad "4" smd rect
			(at 0.899922 0.750062 270)
			(size 0.6096 0.6096)
			(layers "F.Cu" "F.Mask" "F.Paste")
			(net "GND")
		)
		(pad "5" smd rect
			(at 0.899922 0 270)
			(size 0.4064 0.6096)
			(layers "F.Cu" "F.Mask" "F.Paste")
			(net "FPGA_PEX1_MODE_SEL1_D_N")
		)
		(pad "6" smd rect
			(at 0.899922 -0.750062 270)
			(size 0.6096 0.6096)
			(layers "F.Cu" "F.Mask" "F.Paste")
			(net "FPGA_PEX1_MODE_SEL1_D_N")
		)
	)
	(footprint ""
		(layer "F.Cu")
		(at 456.420982 -116.230654 -90)
		(property "Reference" "R959"
			(at 0 0 270)
			(layer "F.SilkS")
			(hide yes)
			(effects
				(font
					(size 1.27 1.27)
				)
			)
		)
		(property "Value" ""
			(at 0 0 270)
			(layer "F.Fab")
			(effects
				(font
					(size 1.27 1.27)
				)
			)
		)
		(duplicate_pad_numbers_are_jumpers no)
		(fp_line
			(start -0.7874 0.4064)
			(end -0.7874 -0.4064)
			(stroke
				(width 0.1524)
				(type default)
			)
			(layer "F.SilkS")
		)
		(fp_line
			(start 0.7874 0.4064)
			(end -0.7874 0.4064)
			(stroke
				(width 0.1524)
				(type default)
			)
			(layer "F.SilkS")
		)
		(fp_line
			(start -0.7874 -0.4064)
			(end 0.7874 -0.4064)
			(stroke
				(width 0.1524)
				(type default)
			)
			(layer "F.SilkS")
		)
		(fp_line
			(start 0.7874 -0.4064)
			(end 0.7874 0.4064)
			(stroke
				(width 0.1524)
				(type default)
			)
			(layer "F.SilkS")
		)
		(fp_line
			(start -0.67945 0.3048)
			(end -0.67945 -0.305054)
			(stroke
				(width 0.1)
				(type default)
			)
			(layer "F.Fab")
		)
		(fp_line
			(start -0.12065 0.3048)
			(end -0.67945 0.3048)
			(stroke
				(width 0.1)
				(type default)
			)
			(layer "F.Fab")
		)
		(fp_line
			(start 0.120396 0.3048)
			(end 0.120396 0.2794)
			(stroke
				(width 0.1)
				(type default)
			)
			(layer "F.Fab")
		)
		(fp_line
			(start 0.67945 0.3048)
			(end 0.120396 0.3048)
			(stroke
				(width 0.1)
				(type default)
			)
			(layer "F.Fab")
		)
		(fp_line
			(start -0.12065 0.2794)
			(end -0.12065 0.3048)
			(stroke
				(width 0.1)
				(type default)
			)
			(layer "F.Fab")
		)
		(fp_line
			(start 0.120396 0.2794)
			(end -0.12065 0.2794)
			(stroke
				(width 0.1)
				(type default)
			)
			(layer "F.Fab")
		)
		(fp_line
			(start -0.12065 -0.2794)
			(end 0.12065 -0.2794)
			(stroke
				(width 0.1)
				(type default)
			)
			(layer "F.Fab")
		)
		(fp_line
			(start 0.12065 -0.2794)
			(end 0.12065 -0.3048)
			(stroke
				(width 0.1)
				(type default)
			)
			(layer "F.Fab")
		)
		(fp_line
			(start 0.12065 -0.3048)
			(end 0.67945 -0.3048)
			(stroke
				(width 0.1)
				(type default)
			)
			(layer "F.Fab")
		)
		(fp_line
			(start 0.67945 -0.3048)
			(end 0.67945 0.3048)
			(stroke
				(width 0.1)
				(type default)
			)
			(layer "F.Fab")
		)
		(fp_line
			(start -0.67945 -0.305054)
			(end -0.12065 -0.305054)
			(stroke
				(width 0.1)
				(type default)
			)
			(layer "F.Fab")
		)
		(fp_line
			(start -0.12065 -0.305054)
			(end -0.12065 -0.2794)
			(stroke
				(width 0.1)
				(type default)
			)
			(layer "F.Fab")
		)
		(pad "1" smd circle
			(at -0.40005 0 270)
			(size 0 0)
			(layers "F.Cu" "F.Mask" "F.Paste")
			(net "P3V3_AUX")
		)
		(pad "2" smd circle
			(at 0.40005 0 270)
			(size 0 0)
			(layers "F.Cu" "F.Mask" "F.Paste")
			(net "PWRGD_P12V_NIC7_CO")
		)
	)
	(footprint ""
		(layer "F.Cu")
		(at 188.759592 -61.612526)
		(property "Reference" "PD32"
			(at -3.695192 -2.648204 0)
			(unlocked yes)
			(layer "F.SilkS")
			(effects
				(font
					(size 0.7874 0.5842)
					(thickness 0.1524)
				)
				(justify left)
			)
		)
		(property "Value" ""
			(at 0 0 0)
			(layer "F.Fab")
			(effects
				(font
					(size 1.27 1.27)
				)
			)
		)
		(duplicate_pad_numbers_are_jumpers no)
		(fp_line
			(start -3.656584 -1.970024)
			(end -3.656584 1.970024)
			(stroke
				(width 0.1524)
				(type default)
			)
			(layer "F.SilkS")
		)
		(fp_line
			(start -3.656584 1.970024)
			(end 4.240784 1.970024)
			(stroke
				(width 0.1524)
				(type default)
			)
			(layer "F.SilkS")
		)
		(fp_line
			(start 4.240784 -1.970024)
			(end -3.656584 -1.970024)
			(stroke
				(width 0.1524)
				(type default)
			)
			(layer "F.SilkS")
		)
		(fp_line
			(start 4.240784 1.970024)
			(end 4.240784 -1.970024)
			(stroke
				(width 0.1524)
				(type default)
			)
			(layer "F.SilkS")
		)
		(fp_poly
			(pts
				(xy 3.580384 1.970024) (xy 3.580384 -1.970024) (xy 4.240784 -1.970024) (xy 4.240784 1.970024)
			)
			(stroke
				(width 0)
				(type default)
			)
			(fill yes)
			(layer "F.SilkS")
		)
		(fp_line
			(start -2.3749 -1.970024)
			(end -2.3749 1.970024)
			(stroke
				(width 0.1)
				(type default)
			)
			(layer "F.Fab")
		)
		(fp_line
			(start -2.3749 1.970024)
			(end 2.3749 1.970024)
			(stroke
				(width 0.1)
				(type default)
			)
			(layer "F.Fab")
		)
		(fp_line
			(start 2.3749 -1.970024)
			(end -2.3749 -1.970024)
			(stroke
				(width 0.1)
				(type default)
			)
			(layer "F.Fab")
		)
		(fp_line
			(start 2.3749 1.970024)
			(end 2.3749 -1.970024)
			(stroke
				(width 0.1)
				(type default)
			)
			(layer "F.Fab")
		)
		(fp_text user "+"
			(at -4.9784 -0.23495 0)
			(unlocked yes)
			(layer "F.Fab")
			(effects
				(font
					(size 1.905 1.4224)
					(thickness 0.1524)
				)
				(justify left)
			)
		)
		(fp_text user "-"
			(at 4.1656 -0.23495 0)
			(unlocked yes)
			(layer "F.Fab")
			(effects
				(font
					(size 1.905 1.4224)
					(thickness 0.1524)
				)
				(justify left)
			)
		)
		(pad "A" smd rect
			(at -2.450084 0)
			(size 2.159 2.2606)
			(layers "F.Cu" "F.Mask" "F.Paste")
			(net "GND")
		)
		(pad "C" smd rect
			(at 2.450084 0)
			(size 2.159 2.2606)
			(layers "F.Cu" "F.Mask" "F.Paste")
			(net "P12V_AUX")
		)
	)
	(footprint ""
		(layer "F.Cu")
		(at 389.50138 -55.78475 -90)
		(property "Reference" "PD43"
			(at 4.01955 2.09931 90)
			(unlocked yes)
			(layer "F.SilkS")
			(effects
				(font
					(size 0.7874 0.5842)
					(thickness 0.1524)
				)
				(justify left)
			)
		)
		(property "Value" ""
			(at 0 0 270)
			(layer "F.Fab")
			(effects
				(font
					(size 1.27 1.27)
				)
			)
		)
		(duplicate_pad_numbers_are_jumpers no)
		(fp_line
			(start -3.400044 1.459992)
			(end -3.400044 -1.459992)
			(stroke
				(width 0.1524)
				(type default)
			)
			(layer "F.SilkS")
		)
		(fp_line
			(start 4.107942 1.459992)
			(end -3.400044 1.459992)
			(stroke
				(width 0.1524)
				(type default)
			)
			(layer "F.SilkS")
		)
		(fp_line
			(start -3.400044 -1.459992)
			(end 4.107942 -1.459992)
			(stroke
				(width 0.1524)
				(type default)
			)
			(layer "F.SilkS")
		)
		(fp_line
			(start 4.107942 -1.459992)
			(end 4.107942 1.459992)
			(stroke
				(width 0.1524)
				(type default)
			)
			(layer "F.SilkS")
		)
		(fp_poly
			(pts
				(xy 4.107942 -1.459992) (xy 4.107942 1.459992) (xy 3.308096 1.459992) (xy 3.308096 -1.459992)
			)
			(stroke
				(width 0)
				(type default)
			)
			(fill yes)
			(layer "F.SilkS")
		)
		(fp_line
			(start -2.29997 1.459992)
			(end -2.29997 -1.459992)
			(stroke
				(width 0.1)
				(type default)
			)
			(layer "F.Fab")
		)
		(fp_line
			(start 2.29997 1.459992)
			(end -2.29997 1.459992)
			(stroke
				(width 0.1)
				(type default)
			)
			(layer "F.Fab")
		)
		(fp_line
			(start -2.29997 -1.459992)
			(end 2.29997 -1.459992)
			(stroke
				(width 0.1)
				(type default)
			)
			(layer "F.Fab")
		)
		(fp_line
			(start 2.29997 -1.459992)
			(end 2.29997 1.459992)
			(stroke
				(width 0.1)
				(type default)
			)
			(layer "F.Fab")
		)
		(fp_text user "-"
			(at 5.4102 0.29845 90)
			(unlocked yes)
			(layer "F.SilkS")
			(effects
				(font
					(size 1.905 1.4224)
					(thickness 0.1524)
				)
				(justify left)
			)
		)
		(fp_text user "+"
			(at -4.7752 -0.12065 270)
			(unlocked yes)
			(layer "F.SilkS")
			(effects
				(font
					(size 1.905 1.4224)
					(thickness 0.1524)
				)
				(justify left)
			)
		)
		(fp_text user "-"
			(at 5.4102 0.29845 90)
			(unlocked yes)
			(layer "F.Fab")
			(effects
				(font
					(size 1.905 1.4224)
					(thickness 0.1524)
				)
				(justify left)
			)
		)
		(fp_text user "+"
			(at -4.7752 -0.12065 270)
			(unlocked yes)
			(layer "F.Fab")
			(effects
				(font
					(size 1.905 1.4224)
					(thickness 0.1524)
				)
				(justify left)
			)
		)
		(pad "A" smd rect
			(at -1.999996 0)
			(size 1.7018 2.5146)
			(layers "F.Cu" "F.Mask" "F.Paste")
			(net "GND")
		)
		(pad "C" smd rect
			(at 1.999996 0)
			(size 1.7018 2.5146)
			(layers "F.Cu" "F.Mask" "F.Paste")
			(net "P12V_SSD13_R")
		)
	)
	(footprint ""
		(layer "F.Cu")
		(at 49.667922 -19.453098)
		(property "Reference" "R1640"
			(at 0 0 0)
			(layer "F.SilkS")
			(hide yes)
			(effects
				(font
					(size 1.27 1.27)
				)
			)
		)
		(property "Value" ""
			(at 0 0 0)
			(layer "F.Fab")
			(effects
				(font
					(size 1.27 1.27)
				)
			)
		)
		(duplicate_pad_numbers_are_jumpers no)
		(fp_line
			(start -0.7874 -0.4064)
			(end 0.7874 -0.4064)
			(stroke
				(width 0.1524)
				(type default)
			)
			(layer "F.SilkS")
		)
		(fp_line
			(start -0.7874 0.4064)
			(end -0.7874 -0.4064)
			(stroke
				(width 0.1524)
				(type default)
			)
			(layer "F.SilkS")
		)
		(fp_line
			(start 0.7874 -0.4064)
			(end 0.7874 0.4064)
			(stroke
				(width 0.1524)
				(type default)
			)
			(layer "F.SilkS")
		)
		(fp_line
			(start 0.7874 0.4064)
			(end -0.7874 0.4064)
			(stroke
				(width 0.1524)
				(type default)
			)
			(layer "F.SilkS")
		)
		(fp_line
			(start -0.67945 -0.305054)
			(end -0.12065 -0.305054)
			(stroke
				(width 0.1)
				(type default)
			)
			(layer "F.Fab")
		)
		(fp_line
			(start -0.67945 0.3048)
			(end -0.67945 -0.305054)
			(stroke
				(width 0.1)
				(type default)
			)
			(layer "F.Fab")
		)
		(fp_line
			(start -0.12065 -0.305054)
			(end -0.12065 -0.2794)
			(stroke
				(width 0.1)
				(type default)
			)
			(layer "F.Fab")
		)
		(fp_line
			(start -0.12065 -0.2794)
			(end 0.12065 -0.2794)
			(stroke
				(width 0.1)
				(type default)
			)
			(layer "F.Fab")
		)
		(fp_line
			(start -0.12065 0.2794)
			(end -0.12065 0.3048)
			(stroke
				(width 0.1)
				(type default)
			)
			(layer "F.Fab")
		)
		(fp_line
			(start -0.12065 0.3048)
			(end -0.67945 0.3048)
			(stroke
				(width 0.1)
				(type default)
			)
			(layer "F.Fab")
		)
		(fp_line
			(start 0.120396 0.2794)
			(end -0.12065 0.2794)
			(stroke
				(width 0.1)
				(type default)
			)
			(layer "F.Fab")
		)
		(fp_line
			(start 0.120396 0.3048)
			(end 0.120396 0.2794)
			(stroke
				(width 0.1)
				(type default)
			)
			(layer "F.Fab")
		)
		(fp_line
			(start 0.12065 -0.3048)
			(end 0.67945 -0.3048)
			(stroke
				(width 0.1)
				(type default)
			)
			(layer "F.Fab")
		)
		(fp_line
			(start 0.12065 -0.2794)
			(end 0.12065 -0.3048)
			(stroke
				(width 0.1)
				(type default)
			)
			(layer "F.Fab")
		)
		(fp_line
			(start 0.67945 -0.3048)
			(end 0.67945 0.3048)
			(stroke
				(width 0.1)
				(type default)
			)
			(layer "F.Fab")
		)
		(fp_line
			(start 0.67945 0.3048)
			(end 0.120396 0.3048)
			(stroke
				(width 0.1)
				(type default)
			)
			(layer "F.Fab")
		)
		(pad "1" smd circle
			(at -0.40005 0)
			(size 0 0)
			(layers "F.Cu" "F.Mask" "F.Paste")
			(net "SMB_ISO_SSD1_R_SDA")
		)
		(pad "2" smd circle
			(at 0.40005 0)
			(size 0 0)
			(layers "F.Cu" "F.Mask" "F.Paste")
			(net "SMB_ISO_SSD1_SDA")
		)
	)
	(footprint ""
		(layer "F.Cu")
		(at 367.826798 -55.418228 90)
		(property "Reference" "PC406"
			(at 0 0 90)
			(layer "F.SilkS")
			(hide yes)
			(effects
				(font
					(size 1.27 1.27)
				)
			)
		)
		(property "Value" ""
			(at 0 0 90)
			(layer "F.Fab")
			(effects
				(font
					(size 1.27 1.27)
				)
			)
		)
		(duplicate_pad_numbers_are_jumpers no)
		(fp_line
			(start 0.7874 -0.4064)
			(end 0.7874 0.4064)
			(stroke
				(width 0.1524)
				(type default)
			)
			(layer "F.SilkS")
		)
		(fp_line
			(start -0.7874 -0.4064)
			(end 0.7874 -0.4064)
			(stroke
				(width 0.1524)
				(type default)
			)
			(layer "F.SilkS")
		)
		(fp_line
			(start 0.7874 0.4064)
			(end -0.7874 0.4064)
			(stroke
				(width 0.1524)
				(type default)
			)
			(layer "F.SilkS")
		)
		(fp_line
			(start -0.7874 0.4064)
			(end -0.7874 -0.4064)
			(stroke
				(width 0.1524)
				(type default)
			)
			(layer "F.SilkS")
		)
		(fp_line
			(start -0.12065 -0.305054)
			(end -0.12065 -0.2794)
			(stroke
				(width 0.1)
				(type default)
			)
			(layer "F.Fab")
		)
		(fp_line
			(start -0.67945 -0.305054)
			(end -0.12065 -0.305054)
			(stroke
				(width 0.1)
				(type default)
			)
			(layer "F.Fab")
		)
		(fp_line
			(start 0.67945 -0.3048)
			(end 0.67945 0.3048)
			(stroke
				(width 0.1)
				(type default)
			)
			(layer "F.Fab")
		)
		(fp_line
			(start 0.12065 -0.3048)
			(end 0.67945 -0.3048)
			(stroke
				(width 0.1)
				(type default)
			)
			(layer "F.Fab")
		)
		(fp_line
			(start 0.12065 -0.2794)
			(end 0.12065 -0.3048)
			(stroke
				(width 0.1)
				(type default)
			)
			(layer "F.Fab")
		)
		(fp_line
			(start -0.12065 -0.2794)
			(end 0.12065 -0.2794)
			(stroke
				(width 0.1)
				(type default)
			)
			(layer "F.Fab")
		)
		(fp_line
			(start 0.120396 0.2794)
			(end -0.12065 0.2794)
			(stroke
				(width 0.1)
				(type default)
			)
			(layer "F.Fab")
		)
		(fp_line
			(start -0.12065 0.2794)
			(end -0.12065 0.3048)
			(stroke
				(width 0.1)
				(type default)
			)
			(layer "F.Fab")
		)
		(fp_line
			(start 0.67945 0.3048)
			(end 0.120396 0.3048)
			(stroke
				(width 0.1)
				(type default)
			)
			(layer "F.Fab")
		)
		(fp_line
			(start 0.120396 0.3048)
			(end 0.120396 0.2794)
			(stroke
				(width 0.1)
				(type default)
			)
			(layer "F.Fab")
		)
		(fp_line
			(start -0.12065 0.3048)
			(end -0.67945 0.3048)
			(stroke
				(width 0.1)
				(type default)
			)
			(layer "F.Fab")
		)
		(fp_line
			(start -0.67945 0.3048)
			(end -0.67945 -0.305054)
			(stroke
				(width 0.1)
				(type default)
			)
			(layer "F.Fab")
		)
		(pad "1" smd circle
			(at -0.40005 0 90)
			(size 0 0)
			(layers "F.Cu" "F.Mask" "F.Paste")
			(net "P12V_SSD12_R")
		)
		(pad "2" smd circle
			(at 0.40005 0 90)
			(size 0 0)
			(layers "F.Cu" "F.Mask" "F.Paste")
			(net "GND")
		)
	)
)
